(kicad_pcb
	(version 20260206)
	(generator "pcbnew")
	(generator_version "10.0")
	(general
		(thickness 1.6)
		(legacy_teardrops no)
	)
	(paper "A4")
	(title_block
		(title "baseboard — 13948-1b.1110WZS1818.brd")
		(comment 1 "Honey Badger (Wiwynn) / footprints 473-479 of 2523")
	)
	(layers
		(0 "F.Cu" signal "TOP")
		(4 "In1.Cu" signal "L2GND")
		(6 "In2.Cu" signal "L3")
		(8 "In3.Cu" signal "L4VCC")
		(10 "In4.Cu" signal "L5VCC")
		(12 "In5.Cu" signal "L6")
		(14 "In6.Cu" signal "L7GND")
		(2 "B.Cu" signal "BOTTOM")
		(9 "F.Adhes" user "F.Adhesive")
		(11 "B.Adhes" user "B.Adhesive")
		(13 "F.Paste" user "Package Geometry/Pastemask Top")
		(15 "B.Paste" user "Package Geometry/Pastemask Bottom")
		(5 "F.SilkS" user "Ref Des/Silkscreen Top")
		(7 "B.SilkS" user "Ref Des/Silkscreen Bottom")
		(1 "F.Mask" user "Board Geometry/Soldermask Top")
		(3 "B.Mask" user "Board Geometry/Soldermask Bottom")
		(17 "Dwgs.User" user "User.Drawings")
		(19 "Cmts.User" user "User.Comments")
		(21 "Eco1.User" user "User.Eco1")
		(23 "Eco2.User" user "User.Eco2")
		(25 "Edge.Cuts" user "Board Geometry/Outline")
		(27 "Margin" user)
		(31 "F.CrtYd" user "Package Geometry/Place Bound Top")
		(29 "B.CrtYd" user "Package Geometry/Place Bound Bottom")
		(35 "F.Fab" user "Ref Des/Assembly Top")
		(33 "B.Fab" user "Ref Des/Assembly Bottom")
	)
	(footprint ""
		(layer "F.Cu")
		(at 141.97457 -93.9546)
		(property "Reference" "R593"
			(at 0 0 0)
			(layer "F.SilkS")
			(hide yes)
			(effects
				(font
					(size 1.27 1.27)
				)
			)
		)
		(property "Value" "0R2J-2-GP"
			(at 0.064008 -3.993896 0)
			(unlocked yes)
			(layer "F.Fab")
			(hide yes)
			(effects
				(font
					(size 1.016 1.016)
					(thickness 0.1524)
				)
			)
		)
		(property "Device Type" "R402H16"
			(at 0.064008 -5.517896 0)
			(unlocked yes)
			(layer "F.Fab")
			(hide yes)
			(effects
				(font
					(size 1.016 1.016)
					(thickness 0.1524)
				)
			)
		)
		(duplicate_pad_numbers_are_jumpers no)
		(fp_line
			(start -0.508 -0.9398)
			(end -0.508 0.9398)
			(stroke
				(width 0.1524)
				(type default)
			)
			(layer "F.SilkS")
		)
		(fp_line
			(start 0.508 -0.9398)
			(end -0.508 -0.9398)
			(stroke
				(width 0.1524)
				(type default)
			)
			(layer "F.SilkS")
		)
		(fp_rect
			(start -0.508 0.9398)
			(end 0.508 -0.9398)
			(stroke
				(width 0)
				(type default)
			)
			(fill no)
			(layer "F.CrtYd")
		)
		(fp_rect
			(start -0.508 0.9398)
			(end 0.508 -0.9398)
			(stroke
				(width 0)
				(type default)
			)
			(fill no)
			(layer "F.Fab")
		)
		(pad "1" smd custom
			(at 0 -0.4445)
			(size 0.1397 0.1397)
			(layers "F.Cu" "F.Mask" "F.Paste")
			(net "BMC_I2C_D_SDA")
			(options
				(clearance outline)
				(anchor circle)
			)
			(primitives
				(gr_poly
					(pts
						(arc
							(start -0.1778 -0.2794)
							(mid -0.249642 -0.249642)
							(end -0.2794 -0.1778)
						)
						(arc
							(start -0.2794 0.1778)
							(mid -0.249642 0.249642)
							(end -0.1778 0.2794)
						)
						(arc
							(start 0.1778 0.2794)
							(mid 0.249642 0.249642)
							(end 0.2794 0.1778)
						)
						(arc
							(start 0.2794 -0.1778)
							(mid 0.249642 -0.249642)
							(end 0.1778 -0.2794)
						)
					)
					(width 0)
					(fill yes)
				)
			)
		)
		(pad "2" smd custom
			(at 0 0.4445)
			(size 0.1397 0.1397)
			(layers "F.Cu" "F.Mask" "F.Paste")
			(net "TEMP_3_SDA")
			(options
				(clearance outline)
				(anchor circle)
			)
			(primitives
				(gr_poly
					(pts
						(arc
							(start -0.1778 -0.2794)
							(mid -0.249642 -0.249642)
							(end -0.2794 -0.1778)
						)
						(arc
							(start -0.2794 0.1778)
							(mid -0.249642 0.249642)
							(end -0.1778 0.2794)
						)
						(arc
							(start 0.1778 0.2794)
							(mid 0.249642 0.249642)
							(end 0.2794 0.1778)
						)
						(arc
							(start 0.2794 -0.1778)
							(mid 0.249642 -0.249642)
							(end 0.1778 -0.2794)
						)
					)
					(width 0)
					(fill yes)
				)
			)
		)
	)
	(footprint ""
		(layer "F.Cu")
		(at 347.599 -98.552 90)
		(property "Reference" "PC15"
			(at 0 0 90)
			(layer "F.SilkS")
			(hide yes)
			(effects
				(font
					(size 1.27 1.27)
				)
			)
		)
		(property "Value" "SC22U10V5MX-GP"
			(at -0.0762 -6.1214 90)
			(unlocked yes)
			(layer "F.Fab")
			(hide yes)
			(effects
				(font
					(size 1.016 1.016)
					(thickness 0.1524)
				)
			)
		)
		(property "Device Type" "C805H56"
			(at -0.0762 -8.1534 90)
			(unlocked yes)
			(layer "F.Fab")
			(hide yes)
			(effects
				(font
					(size 1.016 1.016)
					(thickness 0.1524)
				)
			)
		)
		(duplicate_pad_numbers_are_jumpers no)
		(fp_line
			(start 0.635 0)
			(end -0.635 0)
			(stroke
				(width 0.508)
				(type default)
			)
			(layer "F.SilkS")
		)
		(fp_rect
			(start -0.9652 1.778)
			(end 0.9652 -1.778)
			(stroke
				(width 0)
				(type default)
			)
			(fill no)
			(layer "F.CrtYd")
		)
		(fp_poly
			(pts
				(xy -0.9652 -1.778) (xy 0.9652 -1.778) (xy 0.9652 1.778) (xy -0.9652 1.778)
			)
			(stroke
				(width 0)
				(type default)
			)
			(fill no)
			(layer "F.Fab")
		)
		(pad "1" smd rect
			(at 0 -0.9652 90)
			(size 1.397 1.143)
			(layers "F.Cu" "F.Mask" "F.Paste")
			(net "P5V_STBY")
		)
		(pad "2" smd rect
			(at 0 0.9652 90)
			(size 1.397 1.143)
			(layers "F.Cu" "F.Mask" "F.Paste")
			(net "GND")
		)
	)
	(footprint ""
		(layer "F.Cu")
		(at 332.867 -10.541)
		(property "Reference" "R85"
			(at 0 0 0)
			(layer "F.SilkS")
			(hide yes)
			(effects
				(font
					(size 1.27 1.27)
				)
			)
		)
		(property "Value" "150R2F-1-GP"
			(at 0.064008 -3.993896 0)
			(unlocked yes)
			(layer "F.Fab")
			(hide yes)
			(effects
				(font
					(size 1.016 1.016)
					(thickness 0.1524)
				)
			)
		)
		(property "Device Type" "R402H16"
			(at 0.064008 -5.517896 0)
			(unlocked yes)
			(layer "F.Fab")
			(hide yes)
			(effects
				(font
					(size 1.016 1.016)
					(thickness 0.1524)
				)
			)
		)
		(duplicate_pad_numbers_are_jumpers no)
		(fp_line
			(start -0.508 -0.9398)
			(end -0.508 0.9398)
			(stroke
				(width 0.1524)
				(type default)
			)
			(layer "F.SilkS")
		)
		(fp_line
			(start 0.508 -0.9398)
			(end -0.508 -0.9398)
			(stroke
				(width 0.1524)
				(type default)
			)
			(layer "F.SilkS")
		)
		(fp_rect
			(start -0.508 0.9398)
			(end 0.508 -0.9398)
			(stroke
				(width 0)
				(type default)
			)
			(fill no)
			(layer "F.CrtYd")
		)
		(fp_rect
			(start -0.508 0.9398)
			(end 0.508 -0.9398)
			(stroke
				(width 0)
				(type default)
			)
			(fill no)
			(layer "F.Fab")
		)
		(pad "1" smd custom
			(at 0 -0.4445)
			(size 0.1397 0.1397)
			(layers "F.Cu" "F.Mask" "F.Paste")
			(net "P3V3_STBY")
			(options
				(clearance outline)
				(anchor circle)
			)
			(primitives
				(gr_poly
					(pts
						(arc
							(start -0.1778 -0.2794)
							(mid -0.249642 -0.249642)
							(end -0.2794 -0.1778)
						)
						(arc
							(start -0.2794 0.1778)
							(mid -0.249642 0.249642)
							(end -0.1778 0.2794)
						)
						(arc
							(start 0.1778 0.2794)
							(mid 0.249642 0.249642)
							(end 0.2794 0.1778)
						)
						(arc
							(start 0.2794 -0.1778)
							(mid 0.249642 -0.249642)
							(end 0.1778 -0.2794)
						)
					)
					(width 0)
					(fill yes)
				)
			)
		)
		(pad "2" smd custom
			(at 0 0.4445)
			(size 0.1397 0.1397)
			(layers "F.Cu" "F.Mask" "F.Paste")
			(net "CONSOLE_LED_0")
			(options
				(clearance outline)
				(anchor circle)
			)
			(primitives
				(gr_poly
					(pts
						(arc
							(start -0.1778 -0.2794)
							(mid -0.249642 -0.249642)
							(end -0.2794 -0.1778)
						)
						(arc
							(start -0.2794 0.1778)
							(mid -0.249642 0.249642)
							(end -0.1778 0.2794)
						)
						(arc
							(start 0.1778 0.2794)
							(mid 0.249642 0.249642)
							(end 0.2794 0.1778)
						)
						(arc
							(start 0.2794 -0.1778)
							(mid 0.249642 -0.249642)
							(end 0.1778 -0.2794)
						)
					)
					(width 0)
					(fill yes)
				)
			)
		)
	)
	(footprint ""
		(layer "F.Cu")
		(at 322.190872 -119.071136)
		(property "Reference" "PC29"
			(at 0 0 0)
			(layer "F.SilkS")
			(hide yes)
			(effects
				(font
					(size 1.27 1.27)
				)
			)
		)
		(property "Value" "SC1U10V3KX-4GP-U"
			(at 0 -2.8194 0)
			(unlocked yes)
			(layer "F.Fab")
			(hide yes)
			(effects
				(font
					(size 1.016 1.016)
					(thickness 0.1524)
				)
			)
		)
		(property "Device Type" "C603H36"
			(at 0 -4.3434 0)
			(unlocked yes)
			(layer "F.Fab")
			(hide yes)
			(effects
				(font
					(size 1.016 1.016)
					(thickness 0.1524)
				)
			)
		)
		(duplicate_pad_numbers_are_jumpers no)
		(fp_line
			(start 0.508 0)
			(end -0.508 0)
			(stroke
				(width 0.2032)
				(type default)
			)
			(layer "F.SilkS")
		)
		(fp_rect
			(start -0.5842 1.3335)
			(end 0.5842 -1.3335)
			(stroke
				(width 0)
				(type default)
			)
			(fill no)
			(layer "F.CrtYd")
		)
		(fp_rect
			(start -0.5842 1.3335)
			(end 0.5842 -1.3335)
			(stroke
				(width 0)
				(type default)
			)
			(fill no)
			(layer "F.Fab")
		)
		(pad "1" smd custom
			(at 0 -0.762)
			(size 0.2159 0.2159)
			(layers "F.Cu" "F.Mask" "F.Paste")
			(net "GND")
			(options
				(clearance outline)
				(anchor circle)
			)
			(primitives
				(gr_poly
					(pts
						(arc
							(start -0.3302 -0.4318)
							(mid -0.402042 -0.402042)
							(end -0.4318 -0.3302)
						)
						(arc
							(start -0.4318 0.3302)
							(mid -0.402042 0.402042)
							(end -0.3302 0.4318)
						)
						(arc
							(start 0.3302 0.4318)
							(mid 0.402042 0.402042)
							(end 0.4318 0.3302)
						)
						(arc
							(start 0.4318 -0.3302)
							(mid 0.402042 -0.402042)
							(end 0.3302 -0.4318)
						)
					)
					(width 0)
					(fill yes)
				)
			)
		)
		(pad "2" smd custom
			(at 0 0.762)
			(size 0.2159 0.2159)
			(layers "F.Cu" "F.Mask" "F.Paste")
			(net "P3V3_STBY_VREG")
			(options
				(clearance outline)
				(anchor circle)
			)
			(primitives
				(gr_poly
					(pts
						(arc
							(start -0.3302 -0.4318)
							(mid -0.402042 -0.402042)
							(end -0.4318 -0.3302)
						)
						(arc
							(start -0.4318 0.3302)
							(mid -0.402042 0.402042)
							(end -0.3302 0.4318)
						)
						(arc
							(start 0.3302 0.4318)
							(mid 0.402042 0.402042)
							(end 0.4318 0.3302)
						)
						(arc
							(start 0.4318 -0.3302)
							(mid 0.402042 -0.402042)
							(end 0.3302 -0.4318)
						)
					)
					(width 0)
					(fill yes)
				)
			)
		)
	)
	(footprint ""
		(layer "F.Cu")
		(at 181.728872 -192.146936)
		(property "Reference" "R430"
			(at 0 0 0)
			(layer "F.SilkS")
			(hide yes)
			(effects
				(font
					(size 1.27 1.27)
				)
			)
		)
		(property "Value" "10KR2F-2-GP"
			(at 0.064008 -3.993896 0)
			(unlocked yes)
			(layer "F.Fab")
			(hide yes)
			(effects
				(font
					(size 1.016 1.016)
					(thickness 0.1524)
				)
			)
		)
		(property "Device Type" "R402H16"
			(at 0.064008 -5.517896 0)
			(unlocked yes)
			(layer "F.Fab")
			(hide yes)
			(effects
				(font
					(size 1.016 1.016)
					(thickness 0.1524)
				)
			)
		)
		(duplicate_pad_numbers_are_jumpers no)
		(fp_line
			(start -0.508 -0.9398)
			(end -0.508 0.9398)
			(stroke
				(width 0.1524)
				(type default)
			)
			(layer "F.SilkS")
		)
		(fp_line
			(start 0.508 -0.9398)
			(end -0.508 -0.9398)
			(stroke
				(width 0.1524)
				(type default)
			)
			(layer "F.SilkS")
		)
		(fp_rect
			(start -0.508 0.9398)
			(end 0.508 -0.9398)
			(stroke
				(width 0)
				(type default)
			)
			(fill no)
			(layer "F.CrtYd")
		)
		(fp_rect
			(start -0.508 0.9398)
			(end 0.508 -0.9398)
			(stroke
				(width 0)
				(type default)
			)
			(fill no)
			(layer "F.Fab")
		)
		(pad "1" smd custom
			(at 0 -0.4445)
			(size 0.1397 0.1397)
			(layers "F.Cu" "F.Mask" "F.Paste")
			(net "I2C_C_BUF_READY")
			(options
				(clearance outline)
				(anchor circle)
			)
			(primitives
				(gr_poly
					(pts
						(arc
							(start -0.1778 -0.2794)
							(mid -0.249642 -0.249642)
							(end -0.2794 -0.1778)
						)
						(arc
							(start -0.2794 0.1778)
							(mid -0.249642 0.249642)
							(end -0.1778 0.2794)
						)
						(arc
							(start 0.1778 0.2794)
							(mid 0.249642 0.249642)
							(end 0.2794 0.1778)
						)
						(arc
							(start 0.2794 -0.1778)
							(mid 0.249642 -0.249642)
							(end 0.1778 -0.2794)
						)
					)
					(width 0)
					(fill yes)
				)
			)
		)
		(pad "2" smd custom
			(at 0 0.4445)
			(size 0.1397 0.1397)
			(layers "F.Cu" "F.Mask" "F.Paste")
			(net "P3V3_STBY")
			(options
				(clearance outline)
				(anchor circle)
			)
			(primitives
				(gr_poly
					(pts
						(arc
							(start -0.1778 -0.2794)
							(mid -0.249642 -0.249642)
							(end -0.2794 -0.1778)
						)
						(arc
							(start -0.2794 0.1778)
							(mid -0.249642 0.249642)
							(end -0.1778 0.2794)
						)
						(arc
							(start 0.1778 0.2794)
							(mid 0.249642 0.249642)
							(end 0.2794 0.1778)
						)
						(arc
							(start 0.2794 -0.1778)
							(mid 0.249642 -0.249642)
							(end 0.1778 -0.2794)
						)
					)
					(width 0)
					(fill yes)
				)
			)
		)
	)
	(footprint ""
		(layer "F.Cu")
		(at 268.224 -171.069)
		(property "Reference" "TP82"
			(at 0 0 0)
			(layer "F.SilkS")
			(hide yes)
			(effects
				(font
					(size 1.27 1.27)
				)
			)
		)
		(property "Value" "TPAD28"
			(at 0.0127 -1.8034 0)
			(unlocked yes)
			(layer "F.Fab")
			(hide yes)
			(effects
				(font
					(size 1.016 1.016)
					(thickness 0.1524)
				)
			)
		)
		(property "Device Type" "TPAD28"
			(at 0.0127 -3.3274 0)
			(unlocked yes)
			(layer "F.Fab")
			(hide yes)
			(effects
				(font
					(size 1.016 1.016)
					(thickness 0.1524)
				)
			)
		)
		(duplicate_pad_numbers_are_jumpers no)
		(fp_poly
			(pts
				(arc
					(start 0.3556 0)
					(mid -0.3556 0)
					(end 0.3556 0)
				)
			)
			(stroke
				(width 0)
				(type default)
			)
			(fill no)
			(layer "F.CrtYd")
		)
		(fp_poly
			(pts
				(arc
					(start 0.6096 0)
					(mid -0.6096 0)
					(end 0.6096 0)
				)
			)
			(stroke
				(width 0)
				(type default)
			)
			(fill no)
			(layer "F.Fab")
		)
		(pad "1" smd circle
			(at 0 0)
			(size 0.7112 0.7112)
			(layers "F.Cu" "F.Mask" "F.Paste")
			(net "BMC_MBC_I2C_E_SCL")
		)
	)
	(footprint ""
		(layer "F.Cu")
		(at 162.274504 -24.184356 180)
		(property "Reference" "R419"
			(at 0 0 180)
			(layer "F.SilkS")
			(hide yes)
			(effects
				(font
					(size 1.27 1.27)
				)
			)
		)
		(property "Value" "0R2J-2-GP"
			(at 0.064008 -3.993896 180)
			(unlocked yes)
			(layer "F.Fab")
			(hide yes)
			(effects
				(font
					(size 1.016 1.016)
					(thickness 0.1524)
				)
			)
		)
		(property "Device Type" "R402H16"
			(at 0.064008 -5.517896 180)
			(unlocked yes)
			(layer "F.Fab")
			(hide yes)
			(effects
				(font
					(size 1.016 1.016)
					(thickness 0.1524)
				)
			)
		)
		(duplicate_pad_numbers_are_jumpers no)
		(fp_line
			(start 0.508 -0.9398)
			(end -0.508 -0.9398)
			(stroke
				(width 0.1524)
				(type default)
			)
			(layer "F.SilkS")
		)
		(fp_line
			(start -0.508 -0.9398)
			(end -0.508 0.9398)
			(stroke
				(width 0.1524)
				(type default)
			)
			(layer "F.SilkS")
		)
		(fp_rect
			(start -0.508 0.9398)
			(end 0.508 -0.9398)
			(stroke
				(width 0)
				(type default)
			)
			(fill no)
			(layer "F.CrtYd")
		)
		(fp_rect
			(start -0.508 0.9398)
			(end 0.508 -0.9398)
			(stroke
				(width 0)
				(type default)
			)
			(fill no)
			(layer "F.Fab")
		)
		(pad "1" smd custom
			(at 0 -0.4445 180)
			(size 0.1397 0.1397)
			(layers "F.Cu" "F.Mask" "F.Paste")
			(net "TP_LAN_7")
			(options
				(clearance outline)
				(anchor circle)
			)
			(primitives
				(gr_poly
					(pts
						(arc
							(start -0.1778 -0.2794)
							(mid -0.249642 -0.249642)
							(end -0.2794 -0.1778)
						)
						(arc
							(start -0.2794 0.1778)
							(mid -0.249642 0.249642)
							(end -0.1778 0.2794)
						)
						(arc
							(start 0.1778 0.2794)
							(mid 0.249642 0.249642)
							(end 0.2794 0.1778)
						)
						(arc
							(start 0.2794 -0.1778)
							(mid 0.249642 -0.249642)
							(end 0.1778 -0.2794)
						)
					)
					(width 0)
					(fill yes)
				)
			)
		)
		(pad "2" smd custom
			(at 0 0.4445 180)
			(size 0.1397 0.1397)
			(layers "F.Cu" "F.Mask" "F.Paste")
			(net "GND")
			(options
				(clearance outline)
				(anchor circle)
			)
			(primitives
				(gr_poly
					(pts
						(arc
							(start -0.1778 -0.2794)
							(mid -0.249642 -0.249642)
							(end -0.2794 -0.1778)
						)
						(arc
							(start -0.2794 0.1778)
							(mid -0.249642 0.249642)
							(end -0.1778 0.2794)
						)
						(arc
							(start 0.1778 0.2794)
							(mid 0.249642 0.249642)
							(end 0.2794 0.1778)
						)
						(arc
							(start 0.2794 -0.1778)
							(mid 0.249642 -0.249642)
							(end 0.1778 -0.2794)
						)
					)
					(width 0)
					(fill yes)
				)
			)
		)
	)
)
